(kicad_pcb
	(version 20260206)
	(generator "pcbnew")
	(generator_version "10.0")
	(general
		(thickness 1.6)
		(legacy_teardrops no)
	)
	(paper "A4")
	(title_block
		(title "peb — Lightning_PEB_BRD.brd")
		(comment 1 "Lightning (Wiwynn / Facebook NVMe JBOF) / footprints 100-106 of 2563")
	)
	(layers
		(0 "F.Cu" signal "TOP")
		(4 "In1.Cu" signal "L2GND")
		(6 "In2.Cu" signal "L3")
		(8 "In3.Cu" signal "L4VCC")
		(10 "In4.Cu" signal "L5VCC")
		(12 "In5.Cu" signal "L6")
		(14 "In6.Cu" signal "L7GND")
		(2 "B.Cu" signal "BOTTOM")
		(9 "F.Adhes" user "F.Adhesive")
		(11 "B.Adhes" user "B.Adhesive")
		(13 "F.Paste" user "Package Geometry/Pastemask Top")
		(15 "B.Paste" user "Package Geometry/Pastemask Bottom")
		(5 "F.SilkS" user "Ref Des/Silkscreen Top")
		(7 "B.SilkS" user "Ref Des/Silkscreen Bottom")
		(1 "F.Mask" user "Board Geometry/Soldermask Top")
		(3 "B.Mask" user "Board Geometry/Soldermask Bottom")
		(17 "Dwgs.User" user "User.Drawings")
		(19 "Cmts.User" user "User.Comments")
		(21 "Eco1.User" user "User.Eco1")
		(23 "Eco2.User" user "User.Eco2")
		(25 "Edge.Cuts" user "Board Geometry/Outline")
		(27 "Margin" user)
		(31 "F.CrtYd" user "Package Geometry/Place Bound Top")
		(29 "B.CrtYd" user "Package Geometry/Place Bound Bottom")
		(35 "F.Fab" user "Ref Des/Assembly Top")
		(33 "B.Fab" user "Ref Des/Assembly Bottom")
	)
	(footprint ""
		(layer "F.Cu")
		(at 46.3804 -73.525888 -90)
		(property "Reference" "SC1308"
			(at 0 0 270)
			(layer "F.SilkS")
			(hide yes)
			(effects
				(font
					(size 1.27 1.27)
				)
			)
		)
		(property "Value" "SCD1U16V2KX-3GP"
			(at 1.1811 -2.7051 270)
			(unlocked yes)
			(layer "F.Fab")
			(hide yes)
			(effects
				(font
					(size 1.016 1.016)
					(thickness 0.1524)
				)
			)
		)
		(property "Device Type" "C402H22"
			(at 1.1811 -4.2291 270)
			(unlocked yes)
			(layer "F.Fab")
			(hide yes)
			(effects
				(font
					(size 1.016 1.016)
					(thickness 0.1524)
				)
			)
		)
		(duplicate_pad_numbers_are_jumpers no)
		(fp_rect
			(start -0.4318 0.9525)
			(end 0.4318 -0.9525)
			(stroke
				(width 0)
				(type default)
			)
			(fill no)
			(layer "F.CrtYd")
		)
		(fp_rect
			(start -0.4318 0.9525)
			(end 0.4318 -0.9525)
			(stroke
				(width 0)
				(type default)
			)
			(fill no)
			(layer "F.Fab")
		)
		(pad "1" smd custom
			(at 0 -0.4445 270)
			(size 0.1524 0.1524)
			(layers "F.Cu" "F.Mask" "F.Paste")
			(net "P5V_STBY")
			(options
				(clearance outline)
				(anchor circle)
			)
			(primitives
				(gr_poly
					(pts
						(arc
							(start 0.3048 -0.2032)
							(mid 0.275042 -0.275042)
							(end 0.2032 -0.3048)
						)
						(arc
							(start -0.2032 -0.3048)
							(mid -0.275042 -0.275042)
							(end -0.3048 -0.2032)
						)
						(arc
							(start -0.3048 0.2032)
							(mid -0.275042 0.275042)
							(end -0.2032 0.3048)
						)
						(arc
							(start 0.2032 0.3048)
							(mid 0.275042 0.275042)
							(end 0.3048 0.2032)
						)
					)
					(width 0)
					(fill yes)
				)
			)
		)
		(pad "2" smd custom
			(at 0 0.4445 270)
			(size 0.1524 0.1524)
			(layers "F.Cu" "F.Mask" "F.Paste")
			(net "GND")
			(options
				(clearance outline)
				(anchor circle)
			)
			(primitives
				(gr_poly
					(pts
						(arc
							(start 0.3048 -0.2032)
							(mid 0.275042 -0.275042)
							(end 0.2032 -0.3048)
						)
						(arc
							(start -0.2032 -0.3048)
							(mid -0.275042 -0.275042)
							(end -0.3048 -0.2032)
						)
						(arc
							(start -0.3048 0.2032)
							(mid -0.275042 0.275042)
							(end -0.2032 0.3048)
						)
						(arc
							(start 0.2032 0.3048)
							(mid 0.275042 0.275042)
							(end 0.3048 0.2032)
						)
					)
					(width 0)
					(fill yes)
				)
			)
		)
	)
	(footprint ""
		(layer "F.Cu")
		(at 53.1876 -114.7572)
		(property "Reference" "R542"
			(at 0 0 0)
			(layer "F.SilkS")
			(hide yes)
			(effects
				(font
					(size 1.27 1.27)
				)
			)
		)
		(property "Value" "0R2J-2-GP"
			(at 0.064008 -3.993896 0)
			(unlocked yes)
			(layer "F.Fab")
			(hide yes)
			(effects
				(font
					(size 1.016 1.016)
					(thickness 0.1524)
				)
			)
		)
		(property "Device Type" "R402H16"
			(at 0.064008 -5.517896 0)
			(unlocked yes)
			(layer "F.Fab")
			(hide yes)
			(effects
				(font
					(size 1.016 1.016)
					(thickness 0.1524)
				)
			)
		)
		(duplicate_pad_numbers_are_jumpers no)
		(fp_line
			(start -0.508 -0.9398)
			(end -0.508 0.9398)
			(stroke
				(width 0.1524)
				(type default)
			)
			(layer "F.SilkS")
		)
		(fp_line
			(start 0.508 -0.9398)
			(end -0.508 -0.9398)
			(stroke
				(width 0.1524)
				(type default)
			)
			(layer "F.SilkS")
		)
		(fp_rect
			(start -0.508 0.9398)
			(end 0.508 -0.9398)
			(stroke
				(width 0)
				(type default)
			)
			(fill no)
			(layer "F.CrtYd")
		)
		(fp_rect
			(start -0.508 0.9398)
			(end 0.508 -0.9398)
			(stroke
				(width 0)
				(type default)
			)
			(fill no)
			(layer "F.Fab")
		)
		(pad "1" smd custom
			(at 0 -0.4445)
			(size 0.1397 0.1397)
			(layers "F.Cu" "F.Mask" "F.Paste")
			(net "BMC0_SDA13_R")
			(options
				(clearance outline)
				(anchor circle)
			)
			(primitives
				(gr_poly
					(pts
						(arc
							(start -0.1778 -0.2794)
							(mid -0.249642 -0.249642)
							(end -0.2794 -0.1778)
						)
						(arc
							(start -0.2794 0.1778)
							(mid -0.249642 0.249642)
							(end -0.1778 0.2794)
						)
						(arc
							(start 0.1778 0.2794)
							(mid 0.249642 0.249642)
							(end 0.2794 0.1778)
						)
						(arc
							(start 0.2794 -0.1778)
							(mid 0.249642 -0.249642)
							(end 0.1778 -0.2794)
						)
					)
					(width 0)
					(fill yes)
				)
			)
		)
		(pad "2" smd custom
			(at 0 0.4445)
			(size 0.1397 0.1397)
			(layers "F.Cu" "F.Mask" "F.Paste")
			(net "BMC_I2C13_MINI7_SDA_S")
			(options
				(clearance outline)
				(anchor circle)
			)
			(primitives
				(gr_poly
					(pts
						(arc
							(start -0.1778 -0.2794)
							(mid -0.249642 -0.249642)
							(end -0.2794 -0.1778)
						)
						(arc
							(start -0.2794 0.1778)
							(mid -0.249642 0.249642)
							(end -0.1778 0.2794)
						)
						(arc
							(start 0.1778 0.2794)
							(mid 0.249642 0.249642)
							(end 0.2794 0.1778)
						)
						(arc
							(start 0.2794 -0.1778)
							(mid 0.249642 -0.249642)
							(end 0.1778 -0.2794)
						)
					)
					(width 0)
					(fill yes)
				)
			)
		)
	)
	(footprint ""
		(layer "F.Cu")
		(at 66.1924 -120.5992 180)
		(property "Reference" "R26"
			(at 0 0 180)
			(layer "F.SilkS")
			(hide yes)
			(effects
				(font
					(size 1.27 1.27)
				)
			)
		)
		(property "Value" "0R2J-2-GP"
			(at 0.064008 -3.993896 180)
			(unlocked yes)
			(layer "F.Fab")
			(hide yes)
			(effects
				(font
					(size 1.016 1.016)
					(thickness 0.1524)
				)
			)
		)
		(property "Device Type" "R402H16"
			(at 0.064008 -5.517896 180)
			(unlocked yes)
			(layer "F.Fab")
			(hide yes)
			(effects
				(font
					(size 1.016 1.016)
					(thickness 0.1524)
				)
			)
		)
		(duplicate_pad_numbers_are_jumpers no)
		(fp_line
			(start 0.508 -0.9398)
			(end -0.508 -0.9398)
			(stroke
				(width 0.1524)
				(type default)
			)
			(layer "F.SilkS")
		)
		(fp_line
			(start -0.508 -0.9398)
			(end -0.508 0.9398)
			(stroke
				(width 0.1524)
				(type default)
			)
			(layer "F.SilkS")
		)
		(fp_rect
			(start -0.508 0.9398)
			(end 0.508 -0.9398)
			(stroke
				(width 0)
				(type default)
			)
			(fill no)
			(layer "F.CrtYd")
		)
		(fp_rect
			(start -0.508 0.9398)
			(end 0.508 -0.9398)
			(stroke
				(width 0)
				(type default)
			)
			(fill no)
			(layer "F.Fab")
		)
		(pad "1" smd custom
			(at 0 -0.4445 180)
			(size 0.1397 0.1397)
			(layers "F.Cu" "F.Mask" "F.Paste")
			(net "BMC_I2C4_MINI4_SCL_S")
			(options
				(clearance outline)
				(anchor circle)
			)
			(primitives
				(gr_poly
					(pts
						(arc
							(start -0.1778 -0.2794)
							(mid -0.249642 -0.249642)
							(end -0.2794 -0.1778)
						)
						(arc
							(start -0.2794 0.1778)
							(mid -0.249642 0.249642)
							(end -0.1778 0.2794)
						)
						(arc
							(start 0.1778 0.2794)
							(mid 0.249642 0.249642)
							(end 0.2794 0.1778)
						)
						(arc
							(start 0.2794 -0.1778)
							(mid 0.249642 -0.249642)
							(end 0.1778 -0.2794)
						)
					)
					(width 0)
					(fill yes)
				)
			)
		)
		(pad "2" smd custom
			(at 0 0.4445 180)
			(size 0.1397 0.1397)
			(layers "F.Cu" "F.Mask" "F.Paste")
			(net "BMC_I2C4_MINI4_SCL")
			(options
				(clearance outline)
				(anchor circle)
			)
			(primitives
				(gr_poly
					(pts
						(arc
							(start -0.1778 -0.2794)
							(mid -0.249642 -0.249642)
							(end -0.2794 -0.1778)
						)
						(arc
							(start -0.2794 0.1778)
							(mid -0.249642 0.249642)
							(end -0.1778 0.2794)
						)
						(arc
							(start 0.1778 0.2794)
							(mid 0.249642 0.249642)
							(end 0.2794 0.1778)
						)
						(arc
							(start 0.2794 -0.1778)
							(mid 0.249642 -0.249642)
							(end 0.1778 -0.2794)
						)
					)
					(width 0)
					(fill yes)
				)
			)
		)
	)
	(footprint ""
		(layer "F.Cu")
		(at 23.867872 -95.239078)
		(property "Reference" "Q36"
			(at 0 0 0)
			(layer "F.SilkS")
			(hide yes)
			(effects
				(font
					(size 1.27 1.27)
				)
			)
		)
		(property "Value" "TMBT3904-GP"
			(at 0.10287 -10.29843 0)
			(unlocked yes)
			(layer "F.Fab")
			(hide yes)
			(effects
				(font
					(size 1.016 1.016)
					(thickness 0.1524)
				)
			)
		)
		(property "Device Type" "SOT23CBE2D4H44"
			(at 0.10287 -12.20343 0)
			(unlocked yes)
			(layer "F.Fab")
			(hide yes)
			(effects
				(font
					(size 1.016 1.016)
					(thickness 0.1524)
				)
			)
		)
		(duplicate_pad_numbers_are_jumpers no)
		(fp_line
			(start -1.651 -1.778)
			(end -1.651 1.778)
			(stroke
				(width 0.1524)
				(type default)
			)
			(layer "F.SilkS")
		)
		(fp_line
			(start -1.651 1.778)
			(end 1.651 1.778)
			(stroke
				(width 0.1524)
				(type default)
			)
			(layer "F.SilkS")
		)
		(fp_line
			(start 1.651 -1.778)
			(end -1.651 -1.778)
			(stroke
				(width 0.1524)
				(type default)
			)
			(layer "F.SilkS")
		)
		(fp_line
			(start 1.651 1.778)
			(end 1.651 -1.778)
			(stroke
				(width 0.1524)
				(type default)
			)
			(layer "F.SilkS")
		)
		(fp_poly
			(pts
				(xy -1.778 1.8796) (xy -1.778 -1.8796) (xy 1.778 -1.8796) (xy 1.778 1.8796)
			)
			(stroke
				(width 0)
				(type default)
			)
			(fill no)
			(layer "F.CrtYd")
		)
		(fp_poly
			(pts
				(xy -1.778 1.8796) (xy -1.778 -1.8796) (xy 1.778 -1.8796) (xy 1.778 1.8796)
			)
			(stroke
				(width 0)
				(type default)
			)
			(fill no)
			(layer "F.Fab")
		)
		(pad "B" smd custom
			(at -0.98425 0.9525)
			(size 0.1905 0.1905)
			(layers "F.Cu" "F.Mask" "F.Paste")
			(net "FM_TPM_PRES_RST_N_R")
			(options
				(clearance outline)
				(anchor circle)
			)
			(primitives
				(gr_poly
					(pts
						(arc
							(start -0.1778 0.5715)
							(mid -0.321484 0.511984)
							(end -0.381 0.3683)
						)
						(arc
							(start -0.381 -0.3683)
							(mid -0.321484 -0.511984)
							(end -0.1778 -0.5715)
						)
						(arc
							(start 0.1778 -0.5715)
							(mid 0.321484 -0.511984)
							(end 0.381 -0.3683)
						)
						(arc
							(start 0.381 0.3683)
							(mid 0.321484 0.511984)
							(end 0.1778 0.5715)
						)
					)
					(width 0)
					(fill yes)
				)
			)
		)
		(pad "C" smd custom
			(at 0 -0.9525)
			(size 0.1905 0.1905)
			(layers "F.Cu" "F.Mask" "F.Paste")
			(net "FM_TPM_PRES_RST")
			(options
				(clearance outline)
				(anchor circle)
			)
			(primitives
				(gr_poly
					(pts
						(arc
							(start -0.1778 0.5715)
							(mid -0.321484 0.511984)
							(end -0.381 0.3683)
						)
						(arc
							(start -0.381 -0.3683)
							(mid -0.321484 -0.511984)
							(end -0.1778 -0.5715)
						)
						(arc
							(start 0.1778 -0.5715)
							(mid 0.321484 -0.511984)
							(end 0.381 -0.3683)
						)
						(arc
							(start 0.381 0.3683)
							(mid 0.321484 0.511984)
							(end 0.1778 0.5715)
						)
					)
					(width 0)
					(fill yes)
				)
			)
		)
		(pad "E" smd custom
			(at 0.98425 0.9525)
			(size 0.1905 0.1905)
			(layers "F.Cu" "F.Mask" "F.Paste")
			(net "GND")
			(options
				(clearance outline)
				(anchor circle)
			)
			(primitives
				(gr_poly
					(pts
						(arc
							(start -0.1778 0.5715)
							(mid -0.321484 0.511984)
							(end -0.381 0.3683)
						)
						(arc
							(start -0.381 -0.3683)
							(mid -0.321484 -0.511984)
							(end -0.1778 -0.5715)
						)
						(arc
							(start 0.1778 -0.5715)
							(mid 0.321484 -0.511984)
							(end 0.381 -0.3683)
						)
						(arc
							(start 0.381 0.3683)
							(mid 0.321484 0.511984)
							(end 0.1778 0.5715)
						)
					)
					(width 0)
					(fill yes)
				)
			)
		)
	)
	(footprint ""
		(layer "F.Cu")
		(at 10.9982 -180.6956)
		(property "Reference" "R2102"
			(at 0 0 0)
			(layer "F.SilkS")
			(hide yes)
			(effects
				(font
					(size 1.27 1.27)
				)
			)
		)
		(property "Value" "26K1R2F-2-GP"
			(at 0.064008 -3.993896 0)
			(unlocked yes)
			(layer "F.Fab")
			(hide yes)
			(effects
				(font
					(size 1.016 1.016)
					(thickness 0.1524)
				)
			)
		)
		(property "Device Type" "R402H16"
			(at 0.064008 -5.517896 0)
			(unlocked yes)
			(layer "F.Fab")
			(hide yes)
			(effects
				(font
					(size 1.016 1.016)
					(thickness 0.1524)
				)
			)
		)
		(duplicate_pad_numbers_are_jumpers no)
		(fp_line
			(start -0.508 -0.9398)
			(end -0.508 0.9398)
			(stroke
				(width 0.1524)
				(type default)
			)
			(layer "F.SilkS")
		)
		(fp_line
			(start 0.508 -0.9398)
			(end -0.508 -0.9398)
			(stroke
				(width 0.1524)
				(type default)
			)
			(layer "F.SilkS")
		)
		(fp_rect
			(start -0.508 0.9398)
			(end 0.508 -0.9398)
			(stroke
				(width 0)
				(type default)
			)
			(fill no)
			(layer "F.CrtYd")
		)
		(fp_rect
			(start -0.508 0.9398)
			(end 0.508 -0.9398)
			(stroke
				(width 0)
				(type default)
			)
			(fill no)
			(layer "F.Fab")
		)
		(pad "1" smd custom
			(at 0 -0.4445)
			(size 0.1397 0.1397)
			(layers "F.Cu" "F.Mask" "F.Paste")
			(net "MB0_P12V_PWRGOOD")
			(options
				(clearance outline)
				(anchor circle)
			)
			(primitives
				(gr_poly
					(pts
						(arc
							(start -0.1778 -0.2794)
							(mid -0.249642 -0.249642)
							(end -0.2794 -0.1778)
						)
						(arc
							(start -0.2794 0.1778)
							(mid -0.249642 0.249642)
							(end -0.1778 0.2794)
						)
						(arc
							(start 0.1778 0.2794)
							(mid 0.249642 0.249642)
							(end 0.2794 0.1778)
						)
						(arc
							(start 0.2794 -0.1778)
							(mid 0.249642 -0.249642)
							(end 0.1778 -0.2794)
						)
					)
					(width 0)
					(fill yes)
				)
			)
		)
		(pad "2" smd custom
			(at 0 0.4445)
			(size 0.1397 0.1397)
			(layers "F.Cu" "F.Mask" "F.Paste")
			(net "AGND_CURRENT_MON")
			(options
				(clearance outline)
				(anchor circle)
			)
			(primitives
				(gr_poly
					(pts
						(arc
							(start -0.1778 -0.2794)
							(mid -0.249642 -0.249642)
							(end -0.2794 -0.1778)
						)
						(arc
							(start -0.2794 0.1778)
							(mid -0.249642 0.249642)
							(end -0.1778 0.2794)
						)
						(arc
							(start 0.1778 0.2794)
							(mid 0.249642 0.249642)
							(end 0.2794 0.1778)
						)
						(arc
							(start 0.2794 -0.1778)
							(mid 0.249642 -0.249642)
							(end 0.1778 -0.2794)
						)
					)
					(width 0)
					(fill yes)
				)
			)
		)
	)
	(footprint ""
		(layer "F.Cu")
		(at 176.723802 -71.071232 -90)
		(property "Reference" "PG30"
			(at 0 0 270)
			(layer "F.SilkS")
			(hide yes)
			(effects
				(font
					(size 1.27 1.27)
				)
			)
		)
		(property "Value" "GAP-CLOSE-PWR-3-GP"
			(at 0.0254 -6.5786 270)
			(unlocked yes)
			(layer "F.Fab")
			(hide yes)
			(effects
				(font
					(size 1.016 1.016)
					(thickness 0.1524)
				)
			)
		)
		(property "Device Type" "GAP-CLOSE-PWR-3"
			(at 0.0254 -8.255 270)
			(unlocked yes)
			(layer "F.Fab")
			(hide yes)
			(effects
				(font
					(size 1.016 1.016)
					(thickness 0.1524)
				)
			)
		)
		(duplicate_pad_numbers_are_jumpers no)
		(fp_rect
			(start -0.7112 0.4572)
			(end 0.7112 -0.4572)
			(stroke
				(width 0)
				(type default)
			)
			(fill no)
			(layer "F.CrtYd")
		)
		(fp_poly
			(pts
				(xy -0.7112 -0.4572) (xy 0.7112 -0.4572) (xy 0.7112 0.4572) (xy -0.7112 0.4572)
			)
			(stroke
				(width 0)
				(type default)
			)
			(fill no)
			(layer "F.Fab")
		)
		(pad "1" smd rect
			(at -0.3048 0 270)
			(size 0.6604 0.762)
			(layers "F.Cu" "F.Mask" "F.Paste")
			(net "DUT_AVD_TX")
		)
		(pad "2" smd rect
			(at 0.3048 0 270)
			(size 0.6604 0.762)
			(layers "F.Cu" "F.Mask" "F.Paste")
			(net "P0V9")
		)
	)
	(footprint ""
		(layer "F.Cu")
		(at 53.721 -123.444 -90)
		(property "Reference" "R802"
			(at 0 0 270)
			(layer "F.SilkS")
			(hide yes)
			(effects
				(font
					(size 1.27 1.27)
				)
			)
		)
		(property "Value" "4K7R2F-GP"
			(at 0.064008 -3.993896 270)
			(unlocked yes)
			(layer "F.Fab")
			(hide yes)
			(effects
				(font
					(size 1.016 1.016)
					(thickness 0.1524)
				)
			)
		)
		(property "Device Type" "R402H16"
			(at 0.064008 -5.517896 270)
			(unlocked yes)
			(layer "F.Fab")
			(hide yes)
			(effects
				(font
					(size 1.016 1.016)
					(thickness 0.1524)
				)
			)
		)
		(duplicate_pad_numbers_are_jumpers no)
		(fp_line
			(start -0.508 -0.9398)
			(end -0.508 0.9398)
			(stroke
				(width 0.1524)
				(type default)
			)
			(layer "F.SilkS")
		)
		(fp_line
			(start 0.508 -0.9398)
			(end -0.508 -0.9398)
			(stroke
				(width 0.1524)
				(type default)
			)
			(layer "F.SilkS")
		)
		(fp_rect
			(start -0.508 0.9398)
			(end 0.508 -0.9398)
			(stroke
				(width 0)
				(type default)
			)
			(fill no)
			(layer "F.CrtYd")
		)
		(fp_rect
			(start -0.508 0.9398)
			(end 0.508 -0.9398)
			(stroke
				(width 0)
				(type default)
			)
			(fill no)
			(layer "F.Fab")
		)
		(pad "1" smd custom
			(at 0 -0.4445 270)
			(size 0.1397 0.1397)
			(layers "F.Cu" "F.Mask" "F.Paste")
			(net "P3V3_STBY")
			(options
				(clearance outline)
				(anchor circle)
			)
			(primitives
				(gr_poly
					(pts
						(arc
							(start -0.1778 -0.2794)
							(mid -0.249642 -0.249642)
							(end -0.2794 -0.1778)
						)
						(arc
							(start -0.2794 0.1778)
							(mid -0.249642 0.249642)
							(end -0.1778 0.2794)
						)
						(arc
							(start 0.1778 0.2794)
							(mid 0.249642 0.249642)
							(end 0.2794 0.1778)
						)
						(arc
							(start 0.2794 -0.1778)
							(mid 0.249642 -0.249642)
							(end 0.1778 -0.2794)
						)
					)
					(width 0)
					(fill yes)
				)
			)
		)
		(pad "2" smd custom
			(at 0 0.4445 270)
			(size 0.1397 0.1397)
			(layers "F.Cu" "F.Mask" "F.Paste")
			(net "JTAG_BMC_TDI")
			(options
				(clearance outline)
				(anchor circle)
			)
			(primitives
				(gr_poly
					(pts
						(arc
							(start -0.1778 -0.2794)
							(mid -0.249642 -0.249642)
							(end -0.2794 -0.1778)
						)
						(arc
							(start -0.2794 0.1778)
							(mid -0.249642 0.249642)
							(end -0.1778 0.2794)
						)
						(arc
							(start 0.1778 0.2794)
							(mid 0.249642 0.249642)
							(end 0.2794 0.1778)
						)
						(arc
							(start 0.2794 -0.1778)
							(mid 0.249642 -0.249642)
							(end 0.1778 -0.2794)
						)
					)
					(width 0)
					(fill yes)
				)
			)
		)
	)
)
